# S9S_MB_2U (Grand Teton) — schematic netlist excerpt (pin names and nets, part order shuffled) for the footprints in the layout excerpt that follows; sources: Cadence DE-HDL packaged netlist, KiCad conversion of 03242023_DA0F0TMBIJ0_F0T_Motherboard_J_brd_V01_OCP.brd

C294  Q_CAP  22UF 4V 20% X6S  pkg C0402  page 77 : A = PVCCIN_CPU1 ; B = GND
C980  Q_CAP  10UF 6.3V 20% X6S  pkg C0402  page 74 : A = PVCCIN_CPU0 ; B = GND

(kicad_pcb
	(version 20260206)
	(generator "pcbnew")
	(generator_version "10.0")
	(general
		(thickness 1.6)
		(legacy_teardrops no)
	)
	(paper "A4")
	(title_block
		(title "03242023_DA0F0TMBIJ0_F0T_Motherboard_J_brd_V01_OCP.brd")
		(comment 1 "Grand Teton / footprints 104-105 of 6105")
	)
	(layers
		(0 "F.Cu" signal "TOP")
		(4 "In1.Cu" signal "GND")
		(6 "In2.Cu" signal "IN1")
		(8 "In3.Cu" signal "GND1")
		(10 "In4.Cu" signal "IN2")
		(12 "In5.Cu" signal "GND2")
		(14 "In6.Cu" signal "IN3")
		(16 "In7.Cu" signal "GND3")
		(18 "In8.Cu" signal "VCC")
		(20 "In9.Cu" signal "VCC1")
		(22 "In10.Cu" signal "GND4")
		(24 "In11.Cu" signal "IN4")
		(26 "In12.Cu" signal "GND5")
		(28 "In13.Cu" signal "IN5")
		(30 "In14.Cu" signal "GND6")
		(32 "In15.Cu" signal "IN6")
		(34 "In16.Cu" signal "GND7")
		(2 "B.Cu" signal "BOTTOM")
		(9 "F.Adhes" user "F.Adhesive")
		(11 "B.Adhes" user "B.Adhesive")
		(13 "F.Paste" user "Package Geometry/Pastemask Top")
		(15 "B.Paste" user "Package Geometry/Pastemask Bottom")
		(5 "F.SilkS" user "Ref Des/Silkscreen Top")
		(7 "B.SilkS" user "Ref Des/Silkscreen Bottom")
		(1 "F.Mask" user "Board Geometry/Soldermask Top")
		(3 "B.Mask" user "Board Geometry/Soldermask Bottom")
		(17 "Dwgs.User" user "User.Drawings")
		(19 "Cmts.User" user "User.Comments")
		(21 "Eco1.User" user "User.Eco1")
		(23 "Eco2.User" user "User.Eco2")
		(25 "Edge.Cuts" user "Board Geometry/Outline")
		(27 "Margin" user)
		(31 "F.CrtYd" user "Package Geometry/Place Bound Top")
		(29 "B.CrtYd" user "Package Geometry/Place Bound Bottom")
		(35 "F.Fab" user "Ref Des/Assembly Top")
		(33 "B.Fab" user "Ref Des/Assembly Bottom")
	)
	(footprint ""
		(layer "F.Cu")
		(at 367.44783 -258.726686 90)
		(property "Reference" "C980"
			(at 0 0 90)
			(layer "F.SilkS")
			(hide yes)
			(effects
				(font
					(size 1.27 1.27)
				)
			)
		)
		(property "Value" ""
			(at 0 0 90)
			(layer "F.Fab")
			(effects
				(font
					(size 1.27 1.27)
				)
			)
		)
		(duplicate_pad_numbers_are_jumpers no)
		(fp_line
			(start 0.7874 -0.4064)
			(end 0.7874 0.4064)
			(stroke
				(width 0.1524)
				(type default)
			)
			(layer "F.SilkS")
		)
		(fp_line
			(start -0.7874 -0.4064)
			(end 0.7874 -0.4064)
			(stroke
				(width 0.1524)
				(type default)
			)
			(layer "F.SilkS")
		)
		(fp_line
			(start 0.7874 0.4064)
			(end -0.7874 0.4064)
			(stroke
				(width 0.1524)
				(type default)
			)
			(layer "F.SilkS")
		)
		(fp_line
			(start -0.7874 0.4064)
			(end -0.7874 -0.4064)
			(stroke
				(width 0.1524)
				(type default)
			)
			(layer "F.SilkS")
		)
		(fp_line
			(start -0.12065 -0.305054)
			(end -0.12065 -0.2794)
			(stroke
				(width 0.1)
				(type default)
			)
			(layer "F.Fab")
		)
		(fp_line
			(start -0.67945 -0.305054)
			(end -0.12065 -0.305054)
			(stroke
				(width 0.1)
				(type default)
			)
			(layer "F.Fab")
		)
		(fp_line
			(start 0.67945 -0.3048)
			(end 0.67945 0.3048)
			(stroke
				(width 0.1)
				(type default)
			)
			(layer "F.Fab")
		)
		(fp_line
			(start 0.12065 -0.3048)
			(end 0.67945 -0.3048)
			(stroke
				(width 0.1)
				(type default)
			)
			(layer "F.Fab")
		)
		(fp_line
			(start 0.12065 -0.2794)
			(end 0.12065 -0.3048)
			(stroke
				(width 0.1)
				(type default)
			)
			(layer "F.Fab")
		)
		(fp_line
			(start -0.12065 -0.2794)
			(end 0.12065 -0.2794)
			(stroke
				(width 0.1)
				(type default)
			)
			(layer "F.Fab")
		)
		(fp_line
			(start 0.120396 0.2794)
			(end -0.12065 0.2794)
			(stroke
				(width 0.1)
				(type default)
			)
			(layer "F.Fab")
		)
		(fp_line
			(start -0.12065 0.2794)
			(end -0.12065 0.3048)
			(stroke
				(width 0.1)
				(type default)
			)
			(layer "F.Fab")
		)
		(fp_line
			(start 0.67945 0.3048)
			(end 0.120396 0.3048)
			(stroke
				(width 0.1)
				(type default)
			)
			(layer "F.Fab")
		)
		(fp_line
			(start 0.120396 0.3048)
			(end 0.120396 0.2794)
			(stroke
				(width 0.1)
				(type default)
			)
			(layer "F.Fab")
		)
		(fp_line
			(start -0.12065 0.3048)
			(end -0.67945 0.3048)
			(stroke
				(width 0.1)
				(type default)
			)
			(layer "F.Fab")
		)
		(fp_line
			(start -0.67945 0.3048)
			(end -0.67945 -0.305054)
			(stroke
				(width 0.1)
				(type default)
			)
			(layer "F.Fab")
		)
		(pad "1" smd circle
			(at -0.40005 0 90)
			(size 0 0)
			(layers "F.Cu" "F.Mask" "F.Paste")
			(net "PVCCIN_CPU0")
		)
		(pad "2" smd circle
			(at 0.40005 0 90)
			(size 0 0)
			(layers "F.Cu" "F.Mask" "F.Paste")
			(net "GND")
		)
	)
	(footprint ""
		(layer "F.Cu")
		(at 116.561616 -245.634256 -90)
		(property "Reference" "C294"
			(at 0 0 270)
			(layer "F.SilkS")
			(hide yes)
			(effects
				(font
					(size 1.27 1.27)
				)
			)
		)
		(property "Value" ""
			(at 0 0 270)
			(layer "F.Fab")
			(effects
				(font
					(size 1.27 1.27)
				)
			)
		)
		(duplicate_pad_numbers_are_jumpers no)
		(fp_line
			(start -0.7874 0.4064)
			(end -0.7874 -0.4064)
			(stroke
				(width 0.1524)
				(type default)
			)
			(layer "F.SilkS")
		)
		(fp_line
			(start 0.7874 0.4064)
			(end -0.7874 0.4064)
			(stroke
				(width 0.1524)
				(type default)
			)
			(layer "F.SilkS")
		)
		(fp_line
			(start -0.7874 -0.4064)
			(end 0.7874 -0.4064)
			(stroke
				(width 0.1524)
				(type default)
			)
			(layer "F.SilkS")
		)
		(fp_line
			(start 0.7874 -0.4064)
			(end 0.7874 0.4064)
			(stroke
				(width 0.1524)
				(type default)
			)
			(layer "F.SilkS")
		)
		(fp_line
			(start -0.67945 0.3048)
			(end -0.67945 -0.305054)
			(stroke
				(width 0.1)
				(type default)
			)
			(layer "F.Fab")
		)
		(fp_line
			(start -0.12065 0.3048)
			(end -0.67945 0.3048)
			(stroke
				(width 0.1)
				(type default)
			)
			(layer "F.Fab")
		)
		(fp_line
			(start 0.120396 0.3048)
			(end 0.120396 0.2794)
			(stroke
				(width 0.1)
				(type default)
			)
			(layer "F.Fab")
		)
		(fp_line
			(start 0.67945 0.3048)
			(end 0.120396 0.3048)
			(stroke
				(width 0.1)
				(type default)
			)
			(layer "F.Fab")
		)
		(fp_line
			(start -0.12065 0.2794)
			(end -0.12065 0.3048)
			(stroke
				(width 0.1)
				(type default)
			)
			(layer "F.Fab")
		)
		(fp_line
			(start 0.120396 0.2794)
			(end -0.12065 0.2794)
			(stroke
				(width 0.1)
				(type default)
			)
			(layer "F.Fab")
		)
		(fp_line
			(start -0.12065 -0.2794)
			(end 0.12065 -0.2794)
			(stroke
				(width 0.1)
				(type default)
			)
			(layer "F.Fab")
		)
		(fp_line
			(start 0.12065 -0.2794)
			(end 0.12065 -0.3048)
			(stroke
				(width 0.1)
				(type default)
			)
			(layer "F.Fab")
		)
		(fp_line
			(start 0.12065 -0.3048)
			(end 0.67945 -0.3048)
			(stroke
				(width 0.1)
				(type default)
			)
			(layer "F.Fab")
		)
		(fp_line
			(start 0.67945 -0.3048)
			(end 0.67945 0.3048)
			(stroke
				(width 0.1)
				(type default)
			)
			(layer "F.Fab")
		)
		(fp_line
			(start -0.67945 -0.305054)
			(end -0.12065 -0.305054)
			(stroke
				(width 0.1)
				(type default)
			)
			(layer "F.Fab")
		)
		(fp_line
			(start -0.12065 -0.305054)
			(end -0.12065 -0.2794)
			(stroke
				(width 0.1)
				(type default)
			)
			(layer "F.Fab")
		)
		(pad "1" smd circle
			(at -0.40005 0 270)
			(size 0 0)
			(layers "F.Cu" "F.Mask" "F.Paste")
			(net "PVCCIN_CPU1")
		)
		(pad "2" smd circle
			(at 0.40005 0 270)
			(size 0 0)
			(layers "F.Cu" "F.Mask" "F.Paste")
			(net "GND")
		)
	)
)
